# S9S_MB_2U (Grand Teton) — schematic netlist excerpt (pin names and nets, part order shuffled) for the footprints in the layout excerpt that follows; sources: Cadence DE-HDL packaged netlist, KiCad conversion of 03242023_DA0F0TMBIJ0_F0T_Motherboard_J_brd_V01_OCP.brd

R2414  Q_RES  0 5% CHIP  pkg 0402LF  page 240 : A = SMB_2_BMC_GPU_SDA ; B = SMB_PCIE2_3V3AUX_SDA_R0
R63  Q_RES  33.2 1% CHIP  pkg 0402LF  page 44 : A = PECI_CPU_GTL ; B = PECI_CPU1_GTL_R

(kicad_pcb
	(version 20260206)
	(generator "pcbnew")
	(generator_version "10.0")
	(general
		(thickness 1.6)
		(legacy_teardrops no)
	)
	(paper "A4")
	(title_block
		(title "03242023_DA0F0TMBIJ0_F0T_Motherboard_J_brd_V01_OCP.brd")
		(comment 1 "Grand Teton / footprints 4300-4301 of 6105")
	)
	(layers
		(0 "F.Cu" signal "TOP")
		(4 "In1.Cu" signal "GND")
		(6 "In2.Cu" signal "IN1")
		(8 "In3.Cu" signal "GND1")
		(10 "In4.Cu" signal "IN2")
		(12 "In5.Cu" signal "GND2")
		(14 "In6.Cu" signal "IN3")
		(16 "In7.Cu" signal "GND3")
		(18 "In8.Cu" signal "VCC")
		(20 "In9.Cu" signal "VCC1")
		(22 "In10.Cu" signal "GND4")
		(24 "In11.Cu" signal "IN4")
		(26 "In12.Cu" signal "GND5")
		(28 "In13.Cu" signal "IN5")
		(30 "In14.Cu" signal "GND6")
		(32 "In15.Cu" signal "IN6")
		(34 "In16.Cu" signal "GND7")
		(2 "B.Cu" signal "BOTTOM")
		(9 "F.Adhes" user "F.Adhesive")
		(11 "B.Adhes" user "B.Adhesive")
		(13 "F.Paste" user "Package Geometry/Pastemask Top")
		(15 "B.Paste" user "Package Geometry/Pastemask Bottom")
		(5 "F.SilkS" user "Ref Des/Silkscreen Top")
		(7 "B.SilkS" user "Ref Des/Silkscreen Bottom")
		(1 "F.Mask" user "Board Geometry/Soldermask Top")
		(3 "B.Mask" user "Board Geometry/Soldermask Bottom")
		(17 "Dwgs.User" user "User.Drawings")
		(19 "Cmts.User" user "User.Comments")
		(21 "Eco1.User" user "User.Eco1")
		(23 "Eco2.User" user "User.Eco2")
		(25 "Edge.Cuts" user "Board Geometry/Outline")
		(27 "Margin" user)
		(31 "F.CrtYd" user "Package Geometry/Place Bound Top")
		(29 "B.CrtYd" user "Package Geometry/Place Bound Bottom")
		(35 "F.Fab" user "Ref Des/Assembly Top")
		(33 "B.Fab" user "Ref Des/Assembly Bottom")
	)
	(footprint ""
		(layer "B.Cu")
		(at 75.363324 -190.705232 -90)
		(property "Reference" "R63"
			(at 0 0 90)
			(layer "B.SilkS")
			(hide yes)
			(effects
				(font
					(size 1.27 1.27)
				)
				(justify mirror)
			)
		)
		(property "Value" ""
			(at 0 0 90)
			(layer "B.Fab")
			(effects
				(font
					(size 1.27 1.27)
				)
				(justify mirror)
			)
		)
		(duplicate_pad_numbers_are_jumpers no)
		(fp_line
			(start -0.7874 0.4064)
			(end 0.7874 0.4064)
			(stroke
				(width 0.1524)
				(type default)
			)
			(layer "B.SilkS")
		)
		(fp_line
			(start 0.7874 0.4064)
			(end 0.7874 -0.4064)
			(stroke
				(width 0.1524)
				(type default)
			)
			(layer "B.SilkS")
		)
		(fp_line
			(start -0.7874 -0.4064)
			(end -0.7874 0.4064)
			(stroke
				(width 0.1524)
				(type default)
			)
			(layer "B.SilkS")
		)
		(fp_line
			(start 0.7874 -0.4064)
			(end -0.7874 -0.4064)
			(stroke
				(width 0.1524)
				(type default)
			)
			(layer "B.SilkS")
		)
		(fp_line
			(start -0.67945 0.3048)
			(end -0.120396 0.3048)
			(stroke
				(width 0.1)
				(type default)
			)
			(layer "B.Fab")
		)
		(fp_line
			(start -0.120396 0.3048)
			(end -0.120396 0.2794)
			(stroke
				(width 0.1)
				(type default)
			)
			(layer "B.Fab")
		)
		(fp_line
			(start 0.12065 0.3048)
			(end 0.67945 0.3048)
			(stroke
				(width 0.1)
				(type default)
			)
			(layer "B.Fab")
		)
		(fp_line
			(start 0.67945 0.3048)
			(end 0.67945 -0.305054)
			(stroke
				(width 0.1)
				(type default)
			)
			(layer "B.Fab")
		)
		(fp_line
			(start -0.120396 0.2794)
			(end 0.12065 0.2794)
			(stroke
				(width 0.1)
				(type default)
			)
			(layer "B.Fab")
		)
		(fp_line
			(start 0.12065 0.2794)
			(end 0.12065 0.3048)
			(stroke
				(width 0.1)
				(type default)
			)
			(layer "B.Fab")
		)
		(fp_line
			(start -0.12065 -0.2794)
			(end -0.12065 -0.3048)
			(stroke
				(width 0.1)
				(type default)
			)
			(layer "B.Fab")
		)
		(fp_line
			(start 0.12065 -0.2794)
			(end -0.12065 -0.2794)
			(stroke
				(width 0.1)
				(type default)
			)
			(layer "B.Fab")
		)
		(fp_line
			(start -0.67945 -0.3048)
			(end -0.67945 0.3048)
			(stroke
				(width 0.1)
				(type default)
			)
			(layer "B.Fab")
		)
		(fp_line
			(start -0.12065 -0.3048)
			(end -0.67945 -0.3048)
			(stroke
				(width 0.1)
				(type default)
			)
			(layer "B.Fab")
		)
		(fp_line
			(start 0.12065 -0.305054)
			(end 0.12065 -0.2794)
			(stroke
				(width 0.1)
				(type default)
			)
			(layer "B.Fab")
		)
		(fp_line
			(start 0.67945 -0.305054)
			(end 0.12065 -0.305054)
			(stroke
				(width 0.1)
				(type default)
			)
			(layer "B.Fab")
		)
		(pad "1" smd circle
			(at 0.40005 0 90)
			(size 0 0)
			(layers "B.Cu" "B.Mask" "B.Paste")
			(net "PECI_CPU_GTL")
		)
		(pad "2" smd circle
			(at -0.40005 0 90)
			(size 0 0)
			(layers "B.Cu" "B.Mask" "B.Paste")
			(net "PECI_CPU1_GTL_R")
		)
	)
	(footprint ""
		(layer "B.Cu")
		(at 155.18638 -13.764768 90)
		(property "Reference" "R2414"
			(at 0 0 90)
			(layer "B.SilkS")
			(hide yes)
			(effects
				(font
					(size 1.27 1.27)
				)
				(justify mirror)
			)
		)
		(property "Value" ""
			(at 0 0 90)
			(layer "B.Fab")
			(effects
				(font
					(size 1.27 1.27)
				)
				(justify mirror)
			)
		)
		(duplicate_pad_numbers_are_jumpers no)
		(fp_line
			(start 0.7874 -0.4064)
			(end -0.7874 -0.4064)
			(stroke
				(width 0.1524)
				(type default)
			)
			(layer "B.SilkS")
		)
		(fp_line
			(start -0.7874 -0.4064)
			(end -0.7874 0.4064)
			(stroke
				(width 0.1524)
				(type default)
			)
			(layer "B.SilkS")
		)
		(fp_line
			(start 0.7874 0.4064)
			(end 0.7874 -0.4064)
			(stroke
				(width 0.1524)
				(type default)
			)
			(layer "B.SilkS")
		)
		(fp_line
			(start -0.7874 0.4064)
			(end 0.7874 0.4064)
			(stroke
				(width 0.1524)
				(type default)
			)
			(layer "B.SilkS")
		)
		(fp_line
			(start 0.67945 -0.305054)
			(end 0.12065 -0.305054)
			(stroke
				(width 0.1)
				(type default)
			)
			(layer "B.Fab")
		)
		(fp_line
			(start 0.12065 -0.305054)
			(end 0.12065 -0.2794)
			(stroke
				(width 0.1)
				(type default)
			)
			(layer "B.Fab")
		)
		(fp_line
			(start -0.12065 -0.3048)
			(end -0.67945 -0.3048)
			(stroke
				(width 0.1)
				(type default)
			)
			(layer "B.Fab")
		)
		(fp_line
			(start -0.67945 -0.3048)
			(end -0.67945 0.3048)
			(stroke
				(width 0.1)
				(type default)
			)
			(layer "B.Fab")
		)
		(fp_line
			(start 0.12065 -0.2794)
			(end -0.12065 -0.2794)
			(stroke
				(width 0.1)
				(type default)
			)
			(layer "B.Fab")
		)
		(fp_line
			(start -0.12065 -0.2794)
			(end -0.12065 -0.3048)
			(stroke
				(width 0.1)
				(type default)
			)
			(layer "B.Fab")
		)
		(fp_line
			(start 0.12065 0.2794)
			(end 0.12065 0.3048)
			(stroke
				(width 0.1)
				(type default)
			)
			(layer "B.Fab")
		)
		(fp_line
			(start -0.120396 0.2794)
			(end 0.12065 0.2794)
			(stroke
				(width 0.1)
				(type default)
			)
			(layer "B.Fab")
		)
		(fp_line
			(start 0.67945 0.3048)
			(end 0.67945 -0.305054)
			(stroke
				(width 0.1)
				(type default)
			)
			(layer "B.Fab")
		)
		(fp_line
			(start 0.12065 0.3048)
			(end 0.67945 0.3048)
			(stroke
				(width 0.1)
				(type default)
			)
			(layer "B.Fab")
		)
		(fp_line
			(start -0.120396 0.3048)
			(end -0.120396 0.2794)
			(stroke
				(width 0.1)
				(type default)
			)
			(layer "B.Fab")
		)
		(fp_line
			(start -0.67945 0.3048)
			(end -0.120396 0.3048)
			(stroke
				(width 0.1)
				(type default)
			)
			(layer "B.Fab")
		)
		(pad "1" smd circle
			(at 0.40005 0 270)
			(size 0 0)
			(layers "B.Cu" "B.Mask" "B.Paste")
			(net "SMB_2_BMC_GPU_SDA")
		)
		(pad "2" smd circle
			(at -0.40005 0 270)
			(size 0 0)
			(layers "B.Cu" "B.Mask" "B.Paste")
			(net "SMB_PCIE2_3V3AUX_SDA_R0")
		)
	)
)
